(kicad_pcb
	(version 20241229)
	(generator "pcbnew")
	(generator_version "9.0")
	(general
		(thickness 1.552)
		(legacy_teardrops no)
	)
	(paper "A4")
	(title_block
		(date "2023-07-25")
		(rev "1.1.4")
		(comment 9 "footprints 185-191 of 379")
	)
	(layers
		(0 "F.Cu" signal)
		(4 "In1.Cu" signal)
		(6 "In2.Cu" signal)
		(8 "In3.Cu" signal)
		(10 "In4.Cu" signal)
		(12 "In5.Cu" signal)
		(14 "In6.Cu" signal)
		(2 "B.Cu" signal)
		(9 "F.Adhes" user "F.Adhesive")
		(11 "B.Adhes" user "B.Adhesive")
		(13 "F.Paste" user)
		(15 "B.Paste" user)
		(5 "F.SilkS" user "F.Silkscreen")
		(7 "B.SilkS" user "B.Silkscreen")
		(1 "F.Mask" user)
		(3 "B.Mask" user)
		(17 "Dwgs.User" user "User.Drawings")
		(19 "Cmts.User" user "User.Comments")
		(21 "Eco1.User" user "User.Eco1")
		(23 "Eco2.User" user "User.Eco2")
		(25 "Edge.Cuts" user)
		(27 "Margin" user)
		(31 "F.CrtYd" user "F.Courtyard")
		(29 "B.CrtYd" user "B.Courtyard")
		(35 "F.Fab" user)
		(33 "B.Fab" user)
	)
	(footprint "antmicro-footprints:antmicro-logo_scaled_30mm"
		(layer "F.Cu")
		(at 100.900345 61.139847)
		(property "Reference" "G***"
			(at -7.7 -10.3 0)
			(layer "F.SilkS")
			(hide yes)
			(effects
				(font
					(size 0.65 0.65)
					(thickness 0.1625)
				)
			)
		)
		(property "Value" "LOGO"
			(at -5.3 10.1 0)
			(layer "F.SilkS")
			(hide yes)
			(effects
				(font
					(size 1.524 1.524)
					(thickness 0.3)
				)
			)
		)
		(attr exclude_from_pos_files exclude_from_bom allow_soldermask_bridges)
	)
	(footprint "antmicro-footprints:R_0402_1005Metric"
		(layer "F.Cu")
		(at 85.2 105.15 180)
		(descr "Resistor SMD 0402")
		(tags "resistor SMD 0402")
		(property "Reference" "R61"
			(at -4.23 7.91 0)
			(layer "F.SilkS")
			(effects
				(font
					(size 0.65 0.65)
					(thickness 0.15)
				)
				(justify right bottom)
			)
		)
		(property "Value" "R_75R_0402"
			(at 0 1.4 0)
			(layer "F.Fab")
			(hide yes)
			(effects
				(font
					(size 0.7 0.7)
					(thickness 0.15)
				)
				(justify right bottom)
			)
		)
		(property "Datasheet" "https://www.bourns.com/docs/product-datasheets/cr.pdf"
			(at 0 0 180)
			(layer "F.Fab")
			(hide yes)
			(effects
				(font
					(size 1.27 1.27)
					(thickness 0.15)
				)
			)
		)
		(property "Description" "SMD Chip Resistor, 75 ohm, ± 1%, 62.5 mW, 0402 [1005 Metric], Thick Film, General Purpose"
			(at 0 0 180)
			(layer "F.Fab")
			(hide yes)
			(effects
				(font
					(size 1.27 1.27)
					(thickness 0.15)
				)
			)
		)
		(property "Author" "Antmicro"
			(at 170.4 210.3 0)
			(layer "F.Fab")
			(hide yes)
			(effects
				(font
					(size 1 1)
					(thickness 0.15)
				)
			)
		)
		(property "License" "Apache-2.0"
			(at 170.4 210.3 0)
			(layer "F.Fab")
			(hide yes)
			(effects
				(font
					(size 1 1)
					(thickness 0.15)
				)
			)
		)
		(property "MPN" "CR0402-FX-75R0GLF"
			(at 170.4 210.3 0)
			(layer "F.Fab")
			(hide yes)
			(effects
				(font
					(size 1 1)
					(thickness 0.15)
				)
			)
		)
		(property "Manufacturer" "Bourns"
			(at 170.4 210.3 0)
			(layer "F.Fab")
			(hide yes)
			(effects
				(font
					(size 1 1)
					(thickness 0.15)
				)
			)
		)
		(property "Tolerance" "1%"
			(at 170.4 210.3 0)
			(layer "F.Fab")
			(hide yes)
			(effects
				(font
					(size 1 1)
					(thickness 0.15)
				)
			)
		)
		(property "Val" "75R"
			(at 170.4 210.3 0)
			(layer "F.Fab")
			(hide yes)
			(effects
				(font
					(size 1 1)
					(thickness 0.15)
				)
			)
		)
		(sheetname "/SDI/")
		(sheetfile "sdi.kicad_sch")
		(attr smd)
		(fp_rect
			(start -0.925 -0.47)
			(end 0.925 0.47)
			(stroke
				(width 0.05)
				(type default)
			)
			(fill no)
			(layer "F.CrtYd")
		)
		(fp_rect
			(start -0.5 -0.25)
			(end 0.5 0.25)
			(stroke
				(width 0.15)
				(type solid)
			)
			(fill no)
			(layer "F.Fab")
		)
		(fp_text user "Author: Antmicro"
			(at -0.95 4.169 180)
			(layer "F.Fab")
			(effects
				(font
					(size 0.7 0.7)
					(thickness 0.15)
				)
				(justify left bottom)
			)
		)
		(fp_text user "${REFERENCE}"
			(at -0.95 3.168 180)
			(layer "F.Fab")
			(effects
				(font
					(size 0.7 0.7)
					(thickness 0.15)
				)
				(justify left bottom)
			)
		)
		(fp_text user "License: Apache-2.0"
			(at -0.95 5.169 180)
			(layer "F.Fab")
			(effects
				(font
					(size 0.7 0.7)
					(thickness 0.15)
				)
				(justify left bottom)
			)
		)
		(pad "1" smd roundrect
			(at -0.48 0 180)
			(size 0.59 0.64)
			(layers "F.Cu" "F.Mask" "F.Paste")
			(roundrect_rratio 0.25)
			(net 254 "/SDI/SDI_OUT_N")
			(pintype "passive")
		)
		(pad "2" smd roundrect
			(at 0.48 0 180)
			(size 0.59 0.64)
			(layers "F.Cu" "F.Mask" "F.Paste")
			(roundrect_rratio 0.25)
			(net 251 "/SDI/SDI_OUT_F2")
			(pintype "passive")
		)
	)
	(footprint "antmicro-footprints:R_0402_1005Metric"
		(layer "F.Cu")
		(at 86.1 77.9 90)
		(descr "Resistor SMD 0402")
		(tags "resistor SMD 0402")
		(property "Reference" "R52"
			(at 5.51 -1.27 90)
			(layer "F.SilkS")
			(effects
				(font
					(size 0.65 0.65)
					(thickness 0.15)
				)
				(justify left bottom)
			)
		)
		(property "Value" "R_75R_0402"
			(at 0 1.4 90)
			(layer "F.Fab")
			(hide yes)
			(effects
				(font
					(size 0.7 0.7)
					(thickness 0.15)
				)
				(justify left bottom)
			)
		)
		(property "Datasheet" "https://www.bourns.com/docs/product-datasheets/cr.pdf"
			(at 0 0 90)
			(layer "F.Fab")
			(hide yes)
			(effects
				(font
					(size 1.27 1.27)
					(thickness 0.15)
				)
			)
		)
		(property "Description" "SMD Chip Resistor, 75 ohm, ± 1%, 62.5 mW, 0402 [1005 Metric], Thick Film, General Purpose"
			(at 0 0 90)
			(layer "F.Fab")
			(hide yes)
			(effects
				(font
					(size 1.27 1.27)
					(thickness 0.15)
				)
			)
		)
		(property "Author" "Antmicro"
			(at 164 -8.2 0)
			(layer "F.Fab")
			(hide yes)
			(effects
				(font
					(size 1 1)
					(thickness 0.15)
				)
			)
		)
		(property "License" "Apache-2.0"
			(at 164 -8.2 0)
			(layer "F.Fab")
			(hide yes)
			(effects
				(font
					(size 1 1)
					(thickness 0.15)
				)
			)
		)
		(property "MPN" "CR0402-FX-75R0GLF"
			(at 164 -8.2 0)
			(layer "F.Fab")
			(hide yes)
			(effects
				(font
					(size 1 1)
					(thickness 0.15)
				)
			)
		)
		(property "Manufacturer" "Bourns"
			(at 164 -8.2 0)
			(layer "F.Fab")
			(hide yes)
			(effects
				(font
					(size 1 1)
					(thickness 0.15)
				)
			)
		)
		(property "Tolerance" "1%"
			(at 164 -8.2 0)
			(layer "F.Fab")
			(hide yes)
			(effects
				(font
					(size 1 1)
					(thickness 0.15)
				)
			)
		)
		(property "Val" "75R"
			(at 164 -8.2 0)
			(layer "F.Fab")
			(hide yes)
			(effects
				(font
					(size 1 1)
					(thickness 0.15)
				)
			)
		)
		(sheetname "/SDI/")
		(sheetfile "sdi.kicad_sch")
		(attr smd)
		(fp_rect
			(start -0.925 -0.47)
			(end 0.925 0.47)
			(stroke
				(width 0.05)
				(type default)
			)
			(fill no)
			(layer "F.CrtYd")
		)
		(fp_rect
			(start -0.5 -0.25)
			(end 0.5 0.25)
			(stroke
				(width 0.15)
				(type solid)
			)
			(fill no)
			(layer "F.Fab")
		)
		(fp_text user "Author: Antmicro"
			(at -0.95 4.169 90)
			(layer "F.Fab")
			(effects
				(font
					(size 0.7 0.7)
					(thickness 0.15)
				)
				(justify left bottom)
			)
		)
		(fp_text user "License: Apache-2.0"
			(at -0.95 5.169 90)
			(layer "F.Fab")
			(effects
				(font
					(size 0.7 0.7)
					(thickness 0.15)
				)
				(justify left bottom)
			)
		)
		(fp_text user "${REFERENCE}"
			(at -0.95 3.168 90)
			(layer "F.Fab")
			(effects
				(font
					(size 0.7 0.7)
					(thickness 0.15)
				)
				(justify left bottom)
			)
		)
		(pad "1" smd roundrect
			(at -0.48 0 90)
			(size 0.59 0.64)
			(layers "F.Cu" "F.Mask" "F.Paste")
			(roundrect_rratio 0.25)
			(net 1 "GND")
			(pintype "passive")
		)
		(pad "2" smd roundrect
			(at 0.48 0 90)
			(size 0.59 0.64)
			(layers "F.Cu" "F.Mask" "F.Paste")
			(roundrect_rratio 0.25)
			(net 243 "/SDI/SDI_IN_F")
			(pintype "passive")
		)
	)
	(footprint "antmicro-footprints:TP_SMD_0.75mm"
		(layer "F.Cu")
		(at 148.09 106.5 90)
		(property "Reference" "TP3"
			(at 0.76 0.34 90)
			(layer "F.SilkS")
			(effects
				(font
					(size 0.65 0.65)
					(thickness 0.15)
				)
				(justify left bottom)
			)
		)
		(property "Value" "TP_0.75mm_SMD"
			(at 0 1.2 90)
			(layer "F.Fab")
			(hide yes)
			(effects
				(font
					(size 0.7 0.7)
					(thickness 0.15)
				)
				(justify left bottom)
			)
		)
		(property "Description" "SMT test point"
			(at 0 0 90)
			(layer "F.Fab")
			(hide yes)
			(effects
				(font
					(size 1.27 1.27)
					(thickness 0.15)
				)
			)
		)
		(property "Author" "Antmicro"
			(at 254.59 -41.59 0)
			(layer "F.Fab")
			(hide yes)
			(effects
				(font
					(size 1 1)
					(thickness 0.15)
				)
			)
		)
		(property "License" "Apache-2.0"
			(at 254.59 -41.59 0)
			(layer "F.Fab")
			(hide yes)
			(effects
				(font
					(size 1 1)
					(thickness 0.15)
				)
			)
		)
		(property "MPN" ""
			(at 254.59 -41.59 0)
			(layer "F.Fab")
			(hide yes)
			(effects
				(font
					(size 1 1)
					(thickness 0.15)
				)
			)
		)
		(property "Manufacturer" ""
			(at 254.59 -41.59 0)
			(layer "F.Fab")
			(hide yes)
			(effects
				(font
					(size 1 1)
					(thickness 0.15)
				)
			)
		)
		(sheetname "/Power Supply/")
		(sheetfile "supply.kicad_sch")
		(attr exclude_from_pos_files)
		(fp_circle
			(center 0 0)
			(end 0.475 0)
			(stroke
				(width 0.05)
				(type default)
			)
			(fill no)
			(layer "F.CrtYd")
		)
		(fp_text user "Author: Antmicro"
			(at -0.4 3.901 90)
			(layer "F.Fab")
			(effects
				(font
					(size 0.7 0.7)
					(thickness 0.15)
				)
				(justify left bottom)
			)
		)
		(fp_text user "License: Apache-2.0"
			(at -0.4 5.101 90)
			(layer "F.Fab")
			(effects
				(font
					(size 0.7 0.7)
					(thickness 0.15)
				)
				(justify left bottom)
			)
		)
		(fp_text user "${REFERENCE}"
			(at -0.4 2.7 90)
			(layer "F.Fab")
			(effects
				(font
					(size 0.7 0.7)
					(thickness 0.15)
				)
				(justify left bottom)
			)
		)
		(pad "1" smd circle
			(at 0 0 90)
			(size 0.75 0.75)
			(layers "F.Cu" "F.Mask")
			(net 2 "+3V3")
			(pinfunction "1")
			(pintype "passive")
		)
	)
	(footprint "antmicro-footprints:R_0402_1005Metric"
		(layer "F.Cu")
		(at 123.46 106.16 180)
		(descr "Resistor SMD 0402")
		(tags "resistor SMD 0402")
		(property "Reference" "R97"
			(at 0.88 -0.38 0)
			(layer "F.SilkS")
			(effects
				(font
					(size 0.65 0.65)
					(thickness 0.15)
				)
				(justify right bottom)
			)
		)
		(property "Value" "R_10k_0402"
			(at 0 1.4 0)
			(layer "F.Fab")
			(hide yes)
			(effects
				(font
					(size 0.7 0.7)
					(thickness 0.15)
				)
				(justify right bottom)
			)
		)
		(property "Datasheet" "https://www.bourns.com/docs/product-datasheets/cr.pdf"
			(at 0 0 180)
			(layer "F.Fab")
			(hide yes)
			(effects
				(font
					(size 1.27 1.27)
					(thickness 0.15)
				)
			)
		)
		(property "Description" "SMD Chip Resistor, 10 kohm, ± 1%, 62.5 mW, 0402 [1005 Metric], Thick Film, General Purpose"
			(at 0 0 180)
			(layer "F.Fab")
			(hide yes)
			(effects
				(font
					(size 1.27 1.27)
					(thickness 0.15)
				)
			)
		)
		(property "Author" "Antmicro"
			(at 246.92 212.32 0)
			(layer "F.Fab")
			(hide yes)
			(effects
				(font
					(size 1 1)
					(thickness 0.15)
				)
			)
		)
		(property "License" "Apache-2.0"
			(at 246.92 212.32 0)
			(layer "F.Fab")
			(hide yes)
			(effects
				(font
					(size 1 1)
					(thickness 0.15)
				)
			)
		)
		(property "MPN" "CR0402-FX-1002GLF"
			(at 246.92 212.32 0)
			(layer "F.Fab")
			(hide yes)
			(effects
				(font
					(size 1 1)
					(thickness 0.15)
				)
			)
		)
		(property "Manufacturer" "Bourns"
			(at 246.92 212.32 0)
			(layer "F.Fab")
			(hide yes)
			(effects
				(font
					(size 1 1)
					(thickness 0.15)
				)
			)
		)
		(property "Tolerance" "1%"
			(at 246.92 212.32 0)
			(layer "F.Fab")
			(hide yes)
			(effects
				(font
					(size 1 1)
					(thickness 0.15)
				)
			)
		)
		(property "Val" "10k"
			(at 246.92 212.32 0)
			(layer "F.Fab")
			(hide yes)
			(effects
				(font
					(size 1 1)
					(thickness 0.15)
				)
			)
		)
		(sheetname "/FPGA/")
		(sheetfile "fpga.kicad_sch")
		(attr smd)
		(fp_rect
			(start -0.925 -0.47)
			(end 0.925 0.47)
			(stroke
				(width 0.05)
				(type default)
			)
			(fill no)
			(layer "F.CrtYd")
		)
		(fp_rect
			(start -0.5 -0.25)
			(end 0.5 0.25)
			(stroke
				(width 0.15)
				(type solid)
			)
			(fill no)
			(layer "F.Fab")
		)
		(fp_text user "${REFERENCE}"
			(at -0.95 3.168 180)
			(layer "F.Fab")
			(effects
				(font
					(size 0.7 0.7)
					(thickness 0.15)
				)
				(justify left bottom)
			)
		)
		(fp_text user "License: Apache-2.0"
			(at -0.95 5.169 180)
			(layer "F.Fab")
			(effects
				(font
					(size 0.7 0.7)
					(thickness 0.15)
				)
				(justify left bottom)
			)
		)
		(fp_text user "Author: Antmicro"
			(at -0.95 4.169 180)
			(layer "F.Fab")
			(effects
				(font
					(size 0.7 0.7)
					(thickness 0.15)
				)
				(justify left bottom)
			)
		)
		(pad "1" smd roundrect
			(at -0.48 0 180)
			(size 0.59 0.64)
			(layers "F.Cu" "F.Mask" "F.Paste")
			(roundrect_rratio 0.25)
			(net 1 "GND")
			(pintype "passive")
		)
		(pad "2" smd roundrect
			(at 0.48 0 180)
			(size 0.59 0.64)
			(layers "F.Cu" "F.Mask" "F.Paste")
			(roundrect_rratio 0.25)
			(net 173 "JTAG_EN")
			(pintype "passive")
		)
	)
	(footprint "antmicro-footprints:MP_Pad5.4mm_Drill2.7mm"
		(layer "F.Cu")
		(at 80.03 120.15)
		(descr "Mounting Hole 2.7mm, M2.5")
		(tags "mounting hole 2.7mm m2.5")
		(property "Reference" "MP2"
			(at 0 -2.9 0)
			(layer "F.SilkS")
			(hide yes)
			(effects
				(font
					(size 0.7 0.7)
					(thickness 0.15)
				)
				(justify left bottom)
			)
		)
		(property "Value" "MP_Pad5.4mm_Drill2.7mm"
			(at 0 3.6 0)
			(layer "F.Fab")
			(effects
				(font
					(size 0.7 0.7)
					(thickness 0.15)
				)
				(justify left bottom)
			)
		)
		(property "Description" "Mechanical part"
			(at 0 0 0)
			(layer "F.Fab")
			(hide yes)
			(effects
				(font
					(size 1.27 1.27)
					(thickness 0.15)
				)
			)
		)
		(property "Author" "Antmicro"
			(at 0 0 0)
			(unlocked yes)
			(layer "F.Fab")
			(hide yes)
			(effects
				(font
					(size 1 1)
					(thickness 0.15)
				)
			)
		)
		(property "License" "Apache-2.0"
			(at 0 0 0)
			(unlocked yes)
			(layer "F.Fab")
			(hide yes)
			(effects
				(font
					(size 1 1)
					(thickness 0.15)
				)
			)
		)
		(sheetname "/")
		(sheetfile "sdi-mipi-video-converter.kicad_sch")
		(attr exclude_from_pos_files exclude_from_bom)
		(fp_circle
			(center 0 0)
			(end 2.95 0)
			(stroke
				(width 0.05)
				(type default)
			)
			(fill no)
			(layer "F.CrtYd")
		)
		(fp_text user "Author: Antmicro"
			(at -8.4 7.2 0)
			(layer "F.Fab")
			(effects
				(font
					(size 0.7 0.7)
					(thickness 0.15)
				)
				(justify left bottom)
			)
		)
		(fp_text user "License: Apache-2.0"
			(at -8.4 8.4 0)
			(layer "F.Fab")
			(effects
				(font
					(size 0.7 0.7)
					(thickness 0.15)
				)
				(justify left bottom)
			)
		)
		(fp_text user "${REFERENCE}"
			(at -8.4 6 0)
			(layer "F.Fab")
			(effects
				(font
					(size 0.7 0.7)
					(thickness 0.15)
				)
				(justify left bottom)
			)
		)
		(pad "1" thru_hole circle
			(at 0 0)
			(size 5.4 5.4)
			(drill 2.7)
			(layers "*.Cu" "*.Mask")
			(remove_unused_layers no)
			(net 399 "unconnected-(MP2-Pad1)")
			(pintype "passive+no_connect")
			(solder_paste_margin_ratio -1)
		)
	)
	(footprint "antmicro-footprints:R_0402_1005Metric"
		(layer "F.Cu")
		(at 139.53 57.34 90)
		(descr "Resistor SMD 0402")
		(tags "resistor SMD 0402")
		(property "Reference" "R12"
			(at -1.1 -0.7 90)
			(layer "F.SilkS")
			(effects
				(font
					(size 0.65 0.65)
					(thickness 0.15)
				)
				(justify left bottom)
			)
		)
		(property "Value" "R_1k5_0402"
			(at 0 1.4 90)
			(layer "F.Fab")
			(hide yes)
			(effects
				(font
					(size 0.7 0.7)
					(thickness 0.15)
				)
				(justify left bottom)
			)
		)
		(property "Datasheet" "https://www.bourns.com/docs/product-datasheets/cr.pdf"
			(at 0 0 90)
			(layer "F.Fab")
			(hide yes)
			(effects
				(font
					(size 1.27 1.27)
					(thickness 0.15)
				)
			)
		)
		(property "Description" "SMD Chip Resistor, 1.5 kohm, ± 1%, 62.5 mW, 0402 [1005 Metric], Thick Film, General Purpose"
			(at 0 0 90)
			(layer "F.Fab")
			(hide yes)
			(effects
				(font
					(size 1.27 1.27)
					(thickness 0.15)
				)
			)
		)
		(property "Author" "Antmicro"
			(at 196.87 -82.19 0)
			(layer "F.Fab")
			(hide yes)
			(effects
				(font
					(size 1 1)
					(thickness 0.15)
				)
			)
		)
		(property "License" "Apache-2.0"
			(at 196.87 -82.19 0)
			(layer "F.Fab")
			(hide yes)
			(effects
				(font
					(size 1 1)
					(thickness 0.15)
				)
			)
		)
		(property "MPN" "CR0402-FX-1501GLF"
			(at 196.87 -82.19 0)
			(layer "F.Fab")
			(hide yes)
			(effects
				(font
					(size 1 1)
					(thickness 0.15)
				)
			)
		)
		(property "Manufacturer" "Bourns"
			(at 196.87 -82.19 0)
			(layer "F.Fab")
			(hide yes)
			(effects
				(font
					(size 1 1)
					(thickness 0.15)
				)
			)
		)
		(property "Tolerance" "1%"
			(at 196.87 -82.19 0)
			(layer "F.Fab")
			(hide yes)
			(effects
				(font
					(size 1 1)
					(thickness 0.15)
				)
			)
		)
		(property "Val" "1k5"
			(at 196.87 -82.19 0)
			(layer "F.Fab")
			(hide yes)
			(effects
				(font
					(size 1 1)
					(thickness 0.15)
				)
			)
		)
		(sheetname "/Power Supply/")
		(sheetfile "supply.kicad_sch")
		(attr smd)
		(fp_rect
			(start -0.925 -0.47)
			(end 0.925 0.47)
			(stroke
				(width 0.05)
				(type default)
			)
			(fill no)
			(layer "F.CrtYd")
		)
		(fp_rect
			(start -0.5 -0.25)
			(end 0.5 0.25)
			(stroke
				(width 0.15)
				(type solid)
			)
			(fill no)
			(layer "F.Fab")
		)
		(fp_text user "${REFERENCE}"
			(at -0.95 3.168 90)
			(layer "F.Fab")
			(effects
				(font
					(size 0.7 0.7)
					(thickness 0.15)
				)
				(justify left bottom)
			)
		)
		(fp_text user "License: Apache-2.0"
			(at -0.95 5.169 90)
			(layer "F.Fab")
			(effects
				(font
					(size 0.7 0.7)
					(thickness 0.15)
				)
				(justify left bottom)
			)
		)
		(fp_text user "Author: Antmicro"
			(at -0.95 4.169 90)
			(layer "F.Fab")
			(effects
				(font
					(size 0.7 0.7)
					(thickness 0.15)
				)
				(justify left bottom)
			)
		)
		(pad "1" smd roundrect
			(at -0.48 0 90)
			(size 0.59 0.64)
			(layers "F.Cu" "F.Mask" "F.Paste")
			(roundrect_rratio 0.25)
			(net 263 "Net-(U6-FB)")
			(pintype "passive")
		)
		(pad "2" smd roundrect
			(at 0.48 0 90)
			(size 0.59 0.64)
			(layers "F.Cu" "F.Mask" "F.Paste")
			(roundrect_rratio 0.25)
			(net 1 "GND")
			(pintype "passive")
		)
	)
)
